# BASEBOARD_FAB2 (Tioga Pass) — schematic netlist excerpt (pin names and nets, part order shuffled) for the footprints in the layout excerpt that follows; sources: Cadence DE-HDL packaged netlist, KiCad conversion of Wiwynn_Tioga_Pass_MB.brd

J4B1  SCONN288_H44441004  SCONN  pkg PIP  page 49
  \12v\(1)  = P12V_NVDIMM_DEF
  VSS(93)  = GND
  DQ(4)  = M_D_DQ<5>
  VSS(92)  = GND
  DQ(0)  = M_D_DQ<1>
  VSS(91)  = GND
  DQS9P  = M_D_DQS_DP<9>
  DQS9N  = M_D_DQS_DN<9>
  VSS(90)  = GND
  DQ(6)  = M_D_DQ<7>
  VSS(89)  = GND
  DQ(2)  = M_D_DQ<3>
  VSS(88)  = GND
  DQ(12)  = M_D_DQ<13>
  VSS(87)  = GND
  DQ(8)  = M_D_DQ<9>
  VSS(86)  = GND
  DQS10P  = M_D_DQS_DP<10>
  DQS10N  = M_D_DQS_DN<10>
  VSS(85)  = GND
  DQ(14)  = M_D_DQ<15>
  VSS(84)  = GND
  DQ(10)  = M_D_DQ<11>
  VSS(83)  = GND
  DQ(20)  = M_D_DQ<21>
  VSS(82)  = GND
  DQ(16)  = M_D_DQ<17>
  VSS(81)  = GND
  DQS11P  = M_D_DQS_DP<11>
  DQS11N  = M_D_DQS_DN<11>
  VSS(80)  = GND
  DQ(22)  = M_D_DQ<23>
  VSS(79)  = GND
  DQ(18)  = M_D_DQ<19>
  VSS(78)  = GND
  DQ(28)  = M_D_DQ<29>
  VSS(77)  = GND
  DQ(24)  = M_D_DQ<25>
  VSS(76)  = GND
  DQS12P  = M_D_DQS_DP<12>
  DQS12N  = M_D_DQS_DN<12>
  VSS(75)  = GND
  DQ(30)  = M_D_DQ<31>
  VSS(74)  = GND
  DQ(26)  = M_D_DQ<27>
  VSS(73)  = GND
  CB(4)  = M_D_ECC<5>
  VSS(72)  = GND
  CB(0)  = M_D_ECC<1>
  VSS(71)  = GND
  DQS17P  = M_D_DQS_DP<17>
  DQS17N  = M_D_DQS_DN<17>
  VSS(70)  = GND
  CB(6)  = M_D_ECC<7>
  VSS(69)  = GND
  CB(2)  = M_D_ECC<3>
  VSS(68)  = GND
  RESET_N  = M_DEF_RST_N
  VDD(25)  = PVDDQ_DEF
  CKE(0)  = M_D_CKE<0>
  VDD(24)  = PVDDQ_DEF
  ACT_N  = M_D_ACT_N
  BG(0)  = M_D_BG<0>
  VDD(23)  = PVDDQ_DEF
  A12  = M_D_MA<12>
  A9  = M_D_MA<9>
  VDD(22)  = PVDDQ_DEF
  A8  = M_D_MA<8>
  A6  = M_D_MA<6>
  VDD(21)  = PVDDQ_DEF
  A3  = M_D_MA<3>
  A1  = M_D_MA<1>
  VDD(20)  = PVDDQ_DEF
  CK0P  = M_D_CLK_DP<0>
  CK0N  = M_D_CLK_DN<0>
  VDD(19)  = PVDDQ_DEF
  VTT(1)  = PVTT_DEF
  EVENT_N  = FM_DIMM_EVENT_COD_N
  A0  = M_D_MA<0>
  VDD(18)  = PVDDQ_DEF
  BA(0)  = M_D_BA<0>
  A16_RAS_N  = M_D_MA<16>
  VDD(17)  = PVDDQ_DEF
  S0_N  = M_D_CS_N<0>
  VDD(16)  = PVDDQ_DEF
  A15_CAS_N  = M_D_MA<15>
  ODT(0)  = M_D_ODT<0>
  VDD(15)  = PVDDQ_DEF
  S1_N  = M_D_CS_N<1>
  VDD(14)  = PVDDQ_DEF
  ODT(1)  = M_D_ODT<1>
  VDD(13)  = PVDDQ_DEF
  S2_N_C(0)  = M_D_CS_N<2>
  VSS(67)  = GND
  DQ(36)  = M_D_DQ<37>
  VSS(66)  = GND
  DQ(32)  = M_D_DQ<33>
  VSS(65)  = GND
  DQS13P  = M_D_DQS_DP<13>
  DQS13N  = M_D_DQS_DN<13>
  VSS(64)  = GND
  DQ(38)  = M_D_DQ<39>
  VSS(63)  = GND
  DQ(34)  = M_D_DQ<35>
  VSS(62)  = GND
  DQ(44)  = M_D_DQ<45>
  VSS(61)  = GND
  DQ(40)  = M_D_DQ<41>
  VSS(60)  = GND
  DQS14P  = M_D_DQS_DP<14>
  DQS14N  = M_D_DQS_DN<14>
  VSS(59)  = GND
  DQ(46)  = M_D_DQ<47>
  VSS(58)  = GND
  DQ(42)  = M_D_DQ<43>
  VSS(57)  = GND
  DQ(52)  = M_D_DQ<53>
  VSS(56)  = GND
  DQ(48)  = M_D_DQ<49>
  VSS(55)  = GND
  DQS15P  = M_D_DQS_DP<15>
  DQS15N  = M_D_DQS_DN<15>
  VSS(54)  = GND
  DQ(54)  = M_D_DQ<55>
  VSS(53)  = GND
  DQ(50)  = M_D_DQ<51>
  VSS(52)  = GND
  DQ(60)  = M_D_DQ<61>
  VSS(51)  = GND
  DQ(56)  = M_D_DQ<57>
  VSS(50)  = GND
  DQS16P  = M_D_DQS_DP<16>
  DQS16N  = M_D_DQS_DN<16>
  VSS(49)  = GND
  DQ(62)  = M_D_DQ<63>
  VSS(48)  = GND
  DQ(58)  = M_D_DQ<59>
  VSS(47)  = GND
  SA(0)  = GND
  SA(1)  = GND
  SCL  = SMB_DDR_DEF_VPP_SCL
  VPP(4)  = PVPP_DEF
  VPP(3)  = PVPP_DEF
  RFU(2)  = TP_CH_D_DIMM_D0_RFU_2
  \12v\(0)  = P12V_NVDIMM_DEF
  VREFCA  = M_D_VREF
  VSS(46)  = GND
  DQ(5)  = M_D_DQ<4>
  VSS(45)  = GND
  DQ(1)  = M_D_DQ<0>
  VSS(44)  = GND
  DQS0N  = M_D_DQS_DN<0>
  DQS0P  = M_D_DQS_DP<0>
  VSS(43)  = GND
  DQ(7)  = M_D_DQ<6>
  VSS(42)  = GND
  DQ(3)  = M_D_DQ<2>
  VSS(41)  = GND
  DQ(13)  = M_D_DQ<12>
  VSS(40)  = GND
  DQ(9)  = M_D_DQ<8>
  VSS(39)  = GND
  DQS1N  = M_D_DQS_DN<1>
  DQS1P  = M_D_DQS_DP<1>
  VSS(38)  = GND
  DQ(15)  = M_D_DQ<14>
  VSS(37)  = GND
  DQ(11)  = M_D_DQ<10>
  VSS(36)  = GND
  DQ(21)  = M_D_DQ<20>
  VSS(35)  = GND
  DQ(17)  = M_D_DQ<16>
  VSS(34)  = GND
  DQS2N  = M_D_DQS_DN<2>
  DQS2P  = M_D_DQS_DP<2>
  VSS(33)  = GND
  DQ(23)  = M_D_DQ<22>
  VSS(32)  = GND
  DQ(19)  = M_D_DQ<18>
  VSS(31)  = GND
  DQ(29)  = M_D_DQ<28>
  VSS(30)  = GND
  DQ(25)  = M_D_DQ<24>
  VSS(29)  = GND
  DQS3N  = M_D_DQS_DN<3>
  DQS3P  = M_D_DQS_DP<3>
  VSS(28)  = GND
  DQ(31)  = M_D_DQ<30>
  VSS(27)  = GND
  DQ(27)  = M_D_DQ<26>
  VSS(26)  = GND
  CB(5)  = M_D_ECC<4>
  VSS(25)  = GND
  CB(1)  = M_D_ECC<0>
  VSS(24)  = GND
  DQS8N  = M_D_DQS_DN<8>
  DQS8P  = M_D_DQS_DP<8>
  VSS(23)  = GND
  CB(7)  = M_D_ECC<6>
  VSS(22)  = GND
  CB(3)  = M_D_ECC<2>
  VSS(21)  = GND
  CKE(1)  = M_D_CKE<1>
  VDD(12)  = PVDDQ_DEF
  RFU(0)  = TP_CH_D_DIMM_D0_RFU_0
  VDD(11)  = PVDDQ_DEF
  BG(1)  = M_D_BG<1>
  ALERT_N  = M_D_ALERT_N
  VDD(10)  = PVDDQ_DEF
  A11  = M_D_MA<11>
  A7  = M_D_MA<7>
  VDD(9)  = PVDDQ_DEF
  A5  = M_D_MA<5>
  A4  = M_D_MA<4>
  VDD(8)  = PVDDQ_DEF
  A2  = M_D_MA<2>
  VDD(7)  = PVDDQ_DEF
  CK1P  = M_D_CLK_DP<1>
  CK1N  = M_D_CLK_DN<1>
  VDD(6)  = PVDDQ_DEF
  VTT(0)  = PVTT_DEF
  PAR  = M_D_PAR
  VDD(5)  = PVDDQ_DEF
  BA(1)  = M_D_BA<1>
  A10  = M_D_MA<10>
  VDD(4)  = PVDDQ_DEF
  RFU(1)  = TP_CH_D_DIMM_D0_RFU_1
  A14_WE_N  = M_D_MA<14>
  VDD(3)  = PVDDQ_DEF
  SAVE_N_NC  = FM_ADR_COMPLETE_DEF_N
  VDD(2)  = PVDDQ_DEF
  A13  = M_D_MA<13>
  VDD(1)  = PVDDQ_DEF
  A17  = M_D_MA<17>
  C(2)  = M_D_C<2>
  VDD(0)  = PVDDQ_DEF
  S3_N_C(1)  = M_D_CS_N<3>
  SA(2)  = GND
  VSS(20)  = GND
  DQ(37)  = M_D_DQ<36>
  VSS(19)  = GND
  DQ(33)  = M_D_DQ<32>
  VSS(18)  = GND
  DQS4N  = M_D_DQS_DN<4>
  DQS4P  = M_D_DQS_DP<4>
  VSS(17)  = GND
  DQ(39)  = M_D_DQ<38>
  VSS(16)  = GND
  DQ(35)  = M_D_DQ<34>
  VSS(15)  = GND
  DQ(45)  = M_D_DQ<44>
  VSS(14)  = GND
  DQ(41)  = M_D_DQ<40>
  VSS(13)  = GND
  DQS5N  = M_D_DQS_DN<5>
  DQS5P  = M_D_DQS_DP<5>
  VSS(12)  = GND
  DQ(47)  = M_D_DQ<46>
  VSS(11)  = GND
  DQ(43)  = M_D_DQ<42>
  VSS(10)  = GND
  DQ(53)  = M_D_DQ<52>
  VSS(9)  = GND
  DQ(49)  = M_D_DQ<48>
  VSS(8)  = GND
  DQS6N  = M_D_DQS_DN<6>
  DQS6P  = M_D_DQS_DP<6>
  VSS(7)  = GND
  DQ(55)  = M_D_DQ<54>
  VSS(6)  = GND
  DQ(51)  = M_D_DQ<50>
  VSS(5)  = GND
  DQ(61)  = M_D_DQ<60>
  VSS(4)  = GND
  DQ(57)  = M_D_DQ<56>
  VSS(3)  = GND
  DQS7N  = M_D_DQS_DN<7>
  DQS7P  = M_D_DQS_DP<7>
  VSS(2)  = GND
  DQ(63)  = M_D_DQ<62>
  VSS(1)  = GND
  DQ(59)  = M_D_DQ<58>
  VSS(0)  = GND
  VDDSPD  = PVPP_DEF
  SDA  = SMB_DDR_DEF_VPP_SDA
  VPP(1)  = PVPP_DEF
  VPP(0)  = PVPP_DEF
  VPP(2)  = PVPP_DEF

(kicad_pcb
	(version 20260206)
	(generator "pcbnew")
	(generator_version "10.0")
	(general
		(thickness 1.6)
		(legacy_teardrops no)
	)
	(paper "A4")
	(title_block
		(title "Wiwynn_Tioga_Pass_MB.brd")
		(comment 1 "Tioga Pass / footprint 990 of 4770 (J4B1), pads 252-291 of 291")
	)
	(layers
		(0 "F.Cu" signal "TOP")
		(4 "In1.Cu" signal "L2GND")
		(6 "In2.Cu" signal "L3")
		(8 "In3.Cu" signal "L4GND")
		(10 "In4.Cu" signal "L5")
		(12 "In5.Cu" signal "L6GND")
		(14 "In6.Cu" signal "L7VCC")
		(16 "In7.Cu" signal "L8VCC")
		(18 "In8.Cu" signal "L9GND")
		(20 "In9.Cu" signal "L10")
		(22 "In10.Cu" signal "L11GND")
		(24 "In11.Cu" signal "L12")
		(26 "In12.Cu" signal "L13GND")
		(2 "B.Cu" signal "BOTTOM")
		(9 "F.Adhes" user "F.Adhesive")
		(11 "B.Adhes" user "B.Adhesive")
		(13 "F.Paste" user "Package Geometry/Pastemask Top")
		(15 "B.Paste" user "Package Geometry/Pastemask Bottom")
		(5 "F.SilkS" user "Ref Des/Silkscreen Top")
		(7 "B.SilkS" user "Ref Des/Silkscreen Bottom")
		(1 "F.Mask" user "Board Geometry/Soldermask Top")
		(3 "B.Mask" user "Board Geometry/Soldermask Bottom")
		(17 "Dwgs.User" user "User.Drawings")
		(19 "Cmts.User" user "User.Comments")
		(21 "Eco1.User" user "User.Eco1")
		(23 "Eco2.User" user "User.Eco2")
		(25 "Edge.Cuts" user "Board Geometry/Outline")
		(27 "Margin" user)
		(31 "F.CrtYd" user "Package Geometry/Place Bound Top")
		(29 "B.CrtYd" user "Package Geometry/Place Bound Bottom")
		(35 "F.Fab" user "Ref Des/Assembly Top")
		(33 "B.Fab" user "Ref Des/Assembly Bottom")
	)
	(footprint ""
		(layer "F.Cu")
		(at 194.700398 -133.0706 90)
		(property "Reference" "J4B1"
			(at -5.087112 42.28211 0)
			(unlocked yes)
			(layer "F.SilkS")
			(effects
				(font
					(size 0.7874 0.5842)
					(thickness 0.1524)
				)
				(justify left)
			)
		)
		(property "Value" ""
			(at 0 0 90)
			(layer "F.Fab")
			(effects
				(font
					(size 1.27 1.27)
				)
			)
		)
		(duplicate_pad_numbers_are_jumpers no)
		(pad "249" smd rect
			(at 4.59994 93.49994 90)
			(size 1.8034 0.508)
			(layers "F.Cu" "F.Mask" "F.Paste")
			(net "M_D_DQ<34>")
		)
		(pad "250" smd rect
			(at 4.59994 94.350078 90)
			(size 1.8034 0.508)
			(layers "F.Cu" "F.Mask" "F.Paste")
			(net "GND")
		)
		(pad "251" smd rect
			(at 4.59994 95.199962 90)
			(size 1.8034 0.508)
			(layers "F.Cu" "F.Mask" "F.Paste")
			(net "M_D_DQ<44>")
		)
		(pad "252" smd rect
			(at 4.59994 96.0501 90)
			(size 1.8034 0.508)
			(layers "F.Cu" "F.Mask" "F.Paste")
			(net "GND")
		)
		(pad "253" smd rect
			(at 4.59994 96.899984 90)
			(size 1.8034 0.508)
			(layers "F.Cu" "F.Mask" "F.Paste")
			(net "M_D_DQ<40>")
		)
		(pad "254" smd rect
			(at 4.59994 97.750122 90)
			(size 1.8034 0.508)
			(layers "F.Cu" "F.Mask" "F.Paste")
			(net "GND")
		)
		(pad "255" smd rect
			(at 4.59994 98.600006 90)
			(size 1.8034 0.508)
			(layers "F.Cu" "F.Mask" "F.Paste")
			(net "M_D_DQS_DN<5>")
		)
		(pad "256" smd rect
			(at 4.59994 99.44989 90)
			(size 1.8034 0.508)
			(layers "F.Cu" "F.Mask" "F.Paste")
			(net "M_D_DQS_DP<5>")
		)
		(pad "257" smd rect
			(at 4.59994 100.300028 90)
			(size 1.8034 0.508)
			(layers "F.Cu" "F.Mask" "F.Paste")
			(net "GND")
		)
		(pad "258" smd rect
			(at 4.59994 101.149912 90)
			(size 1.8034 0.508)
			(layers "F.Cu" "F.Mask" "F.Paste")
			(net "M_D_DQ<46>")
		)
		(pad "259" smd rect
			(at 4.59994 102.00005 90)
			(size 1.8034 0.508)
			(layers "F.Cu" "F.Mask" "F.Paste")
			(net "GND")
		)
		(pad "260" smd rect
			(at 4.59994 102.849934 90)
			(size 1.8034 0.508)
			(layers "F.Cu" "F.Mask" "F.Paste")
			(net "M_D_DQ<42>")
		)
		(pad "261" smd rect
			(at 4.59994 103.700072 90)
			(size 1.8034 0.508)
			(layers "F.Cu" "F.Mask" "F.Paste")
			(net "GND")
		)
		(pad "262" smd rect
			(at 4.59994 104.549956 90)
			(size 1.8034 0.508)
			(layers "F.Cu" "F.Mask" "F.Paste")
			(net "M_D_DQ<52>")
		)
		(pad "263" smd rect
			(at 4.59994 105.400094 90)
			(size 1.8034 0.508)
			(layers "F.Cu" "F.Mask" "F.Paste")
			(net "GND")
		)
		(pad "264" smd rect
			(at 4.59994 106.249978 90)
			(size 1.8034 0.508)
			(layers "F.Cu" "F.Mask" "F.Paste")
			(net "M_D_DQ<48>")
		)
		(pad "265" smd rect
			(at 4.59994 107.100116 90)
			(size 1.8034 0.508)
			(layers "F.Cu" "F.Mask" "F.Paste")
			(net "GND")
		)
		(pad "266" smd rect
			(at 4.59994 107.95 90)
			(size 1.8034 0.508)
			(layers "F.Cu" "F.Mask" "F.Paste")
			(net "M_D_DQS_DN<6>")
		)
		(pad "267" smd rect
			(at 4.59994 108.799884 90)
			(size 1.8034 0.508)
			(layers "F.Cu" "F.Mask" "F.Paste")
			(net "M_D_DQS_DP<6>")
		)
		(pad "268" smd rect
			(at 4.59994 109.650022 90)
			(size 1.8034 0.508)
			(layers "F.Cu" "F.Mask" "F.Paste")
			(net "GND")
		)
		(pad "269" smd rect
			(at 4.59994 110.499906 90)
			(size 1.8034 0.508)
			(layers "F.Cu" "F.Mask" "F.Paste")
			(net "M_D_DQ<54>")
		)
		(pad "270" smd rect
			(at 4.59994 111.350044 90)
			(size 1.8034 0.508)
			(layers "F.Cu" "F.Mask" "F.Paste")
			(net "GND")
		)
		(pad "271" smd rect
			(at 4.59994 112.199928 90)
			(size 1.8034 0.508)
			(layers "F.Cu" "F.Mask" "F.Paste")
			(net "M_D_DQ<50>")
		)
		(pad "272" smd rect
			(at 4.59994 113.050066 90)
			(size 1.8034 0.508)
			(layers "F.Cu" "F.Mask" "F.Paste")
			(net "GND")
		)
		(pad "273" smd rect
			(at 4.59994 113.89995 90)
			(size 1.8034 0.508)
			(layers "F.Cu" "F.Mask" "F.Paste")
			(net "M_D_DQ<60>")
		)
		(pad "274" smd rect
			(at 4.59994 114.750088 90)
			(size 1.8034 0.508)
			(layers "F.Cu" "F.Mask" "F.Paste")
			(net "GND")
		)
		(pad "275" smd rect
			(at 4.59994 115.599972 90)
			(size 1.8034 0.508)
			(layers "F.Cu" "F.Mask" "F.Paste")
			(net "M_D_DQ<56>")
		)
		(pad "276" smd rect
			(at 4.59994 116.45011 90)
			(size 1.8034 0.508)
			(layers "F.Cu" "F.Mask" "F.Paste")
			(net "GND")
		)
		(pad "277" smd rect
			(at 4.59994 117.299994 90)
			(size 1.8034 0.508)
			(layers "F.Cu" "F.Mask" "F.Paste")
			(net "M_D_DQS_DN<7>")
		)
		(pad "278" smd rect
			(at 4.59994 118.149878 90)
			(size 1.8034 0.508)
			(layers "F.Cu" "F.Mask" "F.Paste")
			(net "M_D_DQS_DP<7>")
		)
		(pad "279" smd rect
			(at 4.59994 119.000016 90)
			(size 1.8034 0.508)
			(layers "F.Cu" "F.Mask" "F.Paste")
			(net "GND")
		)
		(pad "280" smd rect
			(at 4.59994 119.8499 90)
			(size 1.8034 0.508)
			(layers "F.Cu" "F.Mask" "F.Paste")
			(net "M_D_DQ<62>")
		)
		(pad "281" smd rect
			(at 4.59994 120.700038 90)
			(size 1.8034 0.508)
			(layers "F.Cu" "F.Mask" "F.Paste")
			(net "GND")
		)
		(pad "282" smd rect
			(at 4.59994 121.549922 90)
			(size 1.8034 0.508)
			(layers "F.Cu" "F.Mask" "F.Paste")
			(net "M_D_DQ<58>")
		)
		(pad "283" smd rect
			(at 4.59994 122.40006 90)
			(size 1.8034 0.508)
			(layers "F.Cu" "F.Mask" "F.Paste")
			(net "GND")
		)
		(pad "284" smd rect
			(at 4.59994 123.249944 90)
			(size 1.8034 0.508)
			(layers "F.Cu" "F.Mask" "F.Paste")
			(net "PVPP_DEF")
		)
		(pad "285" smd rect
			(at 4.59994 124.100082 90)
			(size 1.8034 0.508)
			(layers "F.Cu" "F.Mask" "F.Paste")
			(net "SMB_DDR_DEF_VPP_SDA")
		)
		(pad "286" smd rect
			(at 4.59994 124.949966 90)
			(size 1.8034 0.508)
			(layers "F.Cu" "F.Mask" "F.Paste")
			(net "PVPP_DEF")
		)
		(pad "287" smd rect
			(at 4.59994 125.800104 90)
			(size 1.8034 0.508)
			(layers "F.Cu" "F.Mask" "F.Paste")
			(net "PVPP_DEF")
		)
		(pad "288" smd rect
			(at 4.59994 126.649988 90)
			(size 1.8034 0.508)
			(layers "F.Cu" "F.Mask" "F.Paste")
			(net "PVPP_DEF")
		)
	)
)
